(kicad_pcb
	(version 20260206)
	(generator "pcbnew")
	(generator_version "10.0")
	(general
		(thickness 1.6)
		(legacy_teardrops no)
	)
	(paper "A4")
	(title_block
		(title "04192023_DAF0TMB3IC0_F0TG_MB_C_brd_V02_OCP.brd")
		(comment 1 "Grand Teton / footprints 1135-1140 of 8354")
	)
	(layers
		(0 "F.Cu" signal "TOP")
		(4 "In1.Cu" signal "GND")
		(6 "In2.Cu" signal "IN1")
		(8 "In3.Cu" signal "GND1")
		(10 "In4.Cu" signal "IN2")
		(12 "In5.Cu" signal "GND2")
		(14 "In6.Cu" signal "IN3")
		(16 "In7.Cu" signal "GND3")
		(18 "In8.Cu" signal "VCC")
		(20 "In9.Cu" signal "VCC1")
		(22 "In10.Cu" signal "GND4")
		(24 "In11.Cu" signal "IN4")
		(26 "In12.Cu" signal "GND5")
		(28 "In13.Cu" signal "IN5")
		(30 "In14.Cu" signal "GND6")
		(32 "In15.Cu" signal "IN6")
		(34 "In16.Cu" signal "GND7")
		(2 "B.Cu" signal "BOTTOM")
		(9 "F.Adhes" user "F.Adhesive")
		(11 "B.Adhes" user "B.Adhesive")
		(13 "F.Paste" user "Package Geometry/Pastemask Top")
		(15 "B.Paste" user "Package Geometry/Pastemask Bottom")
		(5 "F.SilkS" user "Ref Des/Silkscreen Top")
		(7 "B.SilkS" user "Ref Des/Silkscreen Bottom")
		(1 "F.Mask" user "Board Geometry/Soldermask Top")
		(3 "B.Mask" user "Board Geometry/Soldermask Bottom")
		(17 "Dwgs.User" user "User.Drawings")
		(19 "Cmts.User" user "User.Comments")
		(21 "Eco1.User" user "User.Eco1")
		(23 "Eco2.User" user "User.Eco2")
		(25 "Edge.Cuts" user "Board Geometry/Outline")
		(27 "Margin" user)
		(31 "F.CrtYd" user "Package Geometry/Place Bound Top")
		(29 "B.CrtYd" user "Package Geometry/Place Bound Bottom")
		(35 "F.Fab" user "Ref Des/Assembly Top")
		(33 "B.Fab" user "Ref Des/Assembly Bottom")
	)
	(footprint ""
		(layer "F.Cu")
		(at 164.719 -107.315 180)
		(property "Reference" "R9027"
			(at 0 0 180)
			(layer "F.SilkS")
			(hide yes)
			(effects
				(font
					(size 1.27 1.27)
				)
			)
		)
		(property "Value" ""
			(at 0 0 180)
			(layer "F.Fab")
			(effects
				(font
					(size 1.27 1.27)
				)
			)
		)
		(duplicate_pad_numbers_are_jumpers no)
		(fp_line
			(start 0.7874 0.4064)
			(end -0.7874 0.4064)
			(stroke
				(width 0.1524)
				(type default)
			)
			(layer "F.SilkS")
		)
		(fp_line
			(start 0.7874 -0.4064)
			(end 0.7874 0.4064)
			(stroke
				(width 0.1524)
				(type default)
			)
			(layer "F.SilkS")
		)
		(fp_line
			(start -0.7874 0.4064)
			(end -0.7874 -0.4064)
			(stroke
				(width 0.1524)
				(type default)
			)
			(layer "F.SilkS")
		)
		(fp_line
			(start -0.7874 -0.4064)
			(end 0.7874 -0.4064)
			(stroke
				(width 0.1524)
				(type default)
			)
			(layer "F.SilkS")
		)
		(fp_line
			(start 0.67945 0.3048)
			(end 0.120396 0.3048)
			(stroke
				(width 0.1)
				(type default)
			)
			(layer "F.Fab")
		)
		(fp_line
			(start 0.67945 -0.3048)
			(end 0.67945 0.3048)
			(stroke
				(width 0.1)
				(type default)
			)
			(layer "F.Fab")
		)
		(fp_line
			(start 0.12065 -0.2794)
			(end 0.12065 -0.3048)
			(stroke
				(width 0.1)
				(type default)
			)
			(layer "F.Fab")
		)
		(fp_line
			(start 0.12065 -0.3048)
			(end 0.67945 -0.3048)
			(stroke
				(width 0.1)
				(type default)
			)
			(layer "F.Fab")
		)
		(fp_line
			(start 0.120396 0.3048)
			(end 0.120396 0.2794)
			(stroke
				(width 0.1)
				(type default)
			)
			(layer "F.Fab")
		)
		(fp_line
			(start 0.120396 0.2794)
			(end -0.12065 0.2794)
			(stroke
				(width 0.1)
				(type default)
			)
			(layer "F.Fab")
		)
		(fp_line
			(start -0.12065 0.3048)
			(end -0.67945 0.3048)
			(stroke
				(width 0.1)
				(type default)
			)
			(layer "F.Fab")
		)
		(fp_line
			(start -0.12065 0.2794)
			(end -0.12065 0.3048)
			(stroke
				(width 0.1)
				(type default)
			)
			(layer "F.Fab")
		)
		(fp_line
			(start -0.12065 -0.2794)
			(end 0.12065 -0.2794)
			(stroke
				(width 0.1)
				(type default)
			)
			(layer "F.Fab")
		)
		(fp_line
			(start -0.12065 -0.305054)
			(end -0.12065 -0.2794)
			(stroke
				(width 0.1)
				(type default)
			)
			(layer "F.Fab")
		)
		(fp_line
			(start -0.67945 0.3048)
			(end -0.67945 -0.305054)
			(stroke
				(width 0.1)
				(type default)
			)
			(layer "F.Fab")
		)
		(fp_line
			(start -0.67945 -0.305054)
			(end -0.12065 -0.305054)
			(stroke
				(width 0.1)
				(type default)
			)
			(layer "F.Fab")
		)
		(pad "1" smd circle
			(at -0.40005 0 180)
			(size 0 0)
			(layers "F.Cu" "F.Mask" "F.Paste")
			(net "P3V3_AUX")
		)
		(pad "2" smd circle
			(at 0.40005 0 180)
			(size 0 0)
			(layers "F.Cu" "F.Mask" "F.Paste")
			(net "IRQ_HSC_FAULT_BUF_N")
		)
	)
	(footprint ""
		(layer "F.Cu")
		(at 254.362966 -66.238374)
		(property "Reference" "Q127"
			(at -1.35382 1.881632 0)
			(unlocked yes)
			(layer "F.SilkS")
			(effects
				(font
					(size 0.7874 0.5842)
					(thickness 0.1524)
				)
				(justify left)
			)
		)
		(property "Value" ""
			(at 0 0 0)
			(layer "F.Fab")
			(effects
				(font
					(size 1.27 1.27)
				)
			)
		)
		(duplicate_pad_numbers_are_jumpers no)
		(fp_line
			(start -1.332738 -1.100074)
			(end -0.4826 -1.100074)
			(stroke
				(width 0.1524)
				(type default)
			)
			(layer "F.SilkS")
		)
		(fp_line
			(start -1.332738 1.100074)
			(end -1.332738 -1.100074)
			(stroke
				(width 0.1524)
				(type default)
			)
			(layer "F.SilkS")
		)
		(fp_line
			(start -0.4826 -1.100074)
			(end 0 -0.541274)
			(stroke
				(width 0.1524)
				(type default)
			)
			(layer "F.SilkS")
		)
		(fp_line
			(start 0 -0.541274)
			(end 0.4826 -1.100074)
			(stroke
				(width 0.1524)
				(type default)
			)
			(layer "F.SilkS")
		)
		(fp_line
			(start 0.4826 -1.100074)
			(end 1.332738 -1.100074)
			(stroke
				(width 0.1524)
				(type default)
			)
			(layer "F.SilkS")
		)
		(fp_line
			(start 1.332738 -1.100074)
			(end 1.332738 1.100074)
			(stroke
				(width 0.1524)
				(type default)
			)
			(layer "F.SilkS")
		)
		(fp_line
			(start 1.332738 1.100074)
			(end -1.332738 1.100074)
			(stroke
				(width 0.1524)
				(type default)
			)
			(layer "F.SilkS")
		)
		(fp_poly
			(pts
				(xy -1.909064 -0.755396) (xy -2.61112 -0.404368) (xy -2.61112 -1.106424)
			)
			(stroke
				(width 0)
				(type default)
			)
			(fill yes)
			(layer "F.SilkS")
		)
		(fp_line
			(start -0.674878 -1.100074)
			(end 0.674878 -1.100074)
			(stroke
				(width 0.1)
				(type default)
			)
			(layer "F.Fab")
		)
		(fp_line
			(start -0.674878 1.100074)
			(end -0.674878 -1.100074)
			(stroke
				(width 0.1)
				(type default)
			)
			(layer "F.Fab")
		)
		(fp_line
			(start 0.674878 -1.100074)
			(end 0.674878 1.100074)
			(stroke
				(width 0.1)
				(type default)
			)
			(layer "F.Fab")
		)
		(fp_line
			(start 0.674878 1.100074)
			(end -0.674878 1.100074)
			(stroke
				(width 0.1)
				(type default)
			)
			(layer "F.Fab")
		)
		(fp_poly
			(pts
				(xy -2.2352 -0.298958) (xy -2.2352 -1.001014) (xy -1.533144 -0.649986)
			)
			(stroke
				(width 0)
				(type default)
			)
			(fill yes)
			(layer "F.Fab")
		)
		(pad "1" smd rect
			(at -0.94996 -0.649986 90)
			(size 0.4318 0.508)
			(layers "F.Cu" "F.Mask" "F.Paste")
			(net "GND")
		)
		(pad "2" smd rect
			(at -0.94996 0 90)
			(size 0.4318 0.508)
			(layers "F.Cu" "F.Mask" "F.Paste")
			(net "P12V_E1S_EN_0_R")
		)
		(pad "3" smd rect
			(at -0.94996 0.649986 90)
			(size 0.4318 0.508)
			(layers "F.Cu" "F.Mask" "F.Paste")
			(net "P12V_E1S_UV_0_R")
		)
		(pad "4" smd rect
			(at 0.94996 0.649986 90)
			(size 0.4318 0.508)
			(layers "F.Cu" "F.Mask" "F.Paste")
			(net "GND")
		)
		(pad "5" smd rect
			(at 0.94996 0 90)
			(size 0.4318 0.508)
			(layers "F.Cu" "F.Mask" "F.Paste")
			(net "P12V_E1S_0_EN_G")
		)
		(pad "6" smd rect
			(at 0.94996 -0.649986 90)
			(size 0.4318 0.508)
			(layers "F.Cu" "F.Mask" "F.Paste")
			(net "P12V_E1S_0_EN_G")
		)
	)
	(footprint ""
		(layer "F.Cu")
		(at 369.00231 -182.602378 90)
		(property "Reference" "PC480_2"
			(at 0 0 90)
			(layer "F.SilkS")
			(hide yes)
			(effects
				(font
					(size 1.27 1.27)
				)
			)
		)
		(property "Value" ""
			(at 0 0 90)
			(layer "F.Fab")
			(effects
				(font
					(size 1.27 1.27)
				)
			)
		)
		(duplicate_pad_numbers_are_jumpers no)
		(fp_line
			(start 0.7874 -0.4064)
			(end 0.7874 0.4064)
			(stroke
				(width 0.1524)
				(type default)
			)
			(layer "F.SilkS")
		)
		(fp_line
			(start -0.7874 -0.4064)
			(end 0.7874 -0.4064)
			(stroke
				(width 0.1524)
				(type default)
			)
			(layer "F.SilkS")
		)
		(fp_line
			(start 0.7874 0.4064)
			(end -0.7874 0.4064)
			(stroke
				(width 0.1524)
				(type default)
			)
			(layer "F.SilkS")
		)
		(fp_line
			(start -0.7874 0.4064)
			(end -0.7874 -0.4064)
			(stroke
				(width 0.1524)
				(type default)
			)
			(layer "F.SilkS")
		)
		(fp_line
			(start -0.12065 -0.305054)
			(end -0.12065 -0.2794)
			(stroke
				(width 0.1)
				(type default)
			)
			(layer "F.Fab")
		)
		(fp_line
			(start -0.67945 -0.305054)
			(end -0.12065 -0.305054)
			(stroke
				(width 0.1)
				(type default)
			)
			(layer "F.Fab")
		)
		(fp_line
			(start 0.67945 -0.3048)
			(end 0.67945 0.3048)
			(stroke
				(width 0.1)
				(type default)
			)
			(layer "F.Fab")
		)
		(fp_line
			(start 0.12065 -0.3048)
			(end 0.67945 -0.3048)
			(stroke
				(width 0.1)
				(type default)
			)
			(layer "F.Fab")
		)
		(fp_line
			(start 0.12065 -0.2794)
			(end 0.12065 -0.3048)
			(stroke
				(width 0.1)
				(type default)
			)
			(layer "F.Fab")
		)
		(fp_line
			(start -0.12065 -0.2794)
			(end 0.12065 -0.2794)
			(stroke
				(width 0.1)
				(type default)
			)
			(layer "F.Fab")
		)
		(fp_line
			(start 0.120396 0.2794)
			(end -0.12065 0.2794)
			(stroke
				(width 0.1)
				(type default)
			)
			(layer "F.Fab")
		)
		(fp_line
			(start -0.12065 0.2794)
			(end -0.12065 0.3048)
			(stroke
				(width 0.1)
				(type default)
			)
			(layer "F.Fab")
		)
		(fp_line
			(start 0.67945 0.3048)
			(end 0.120396 0.3048)
			(stroke
				(width 0.1)
				(type default)
			)
			(layer "F.Fab")
		)
		(fp_line
			(start 0.120396 0.3048)
			(end 0.120396 0.2794)
			(stroke
				(width 0.1)
				(type default)
			)
			(layer "F.Fab")
		)
		(fp_line
			(start -0.12065 0.3048)
			(end -0.67945 0.3048)
			(stroke
				(width 0.1)
				(type default)
			)
			(layer "F.Fab")
		)
		(fp_line
			(start -0.67945 0.3048)
			(end -0.67945 -0.305054)
			(stroke
				(width 0.1)
				(type default)
			)
			(layer "F.Fab")
		)
		(pad "1" smd circle
			(at -0.40005 0 90)
			(size 0 0)
			(layers "F.Cu" "F.Mask" "F.Paste")
			(net "SW_P12V_AUX_PVDDCR_CPU0_P0_FLT")
		)
		(pad "2" smd circle
			(at 0.40005 0 90)
			(size 0 0)
			(layers "F.Cu" "F.Mask" "F.Paste")
			(net "GND")
		)
	)
	(footprint ""
		(layer "F.Cu")
		(at 326.992488 -394.82268 90)
		(property "Reference" "C504"
			(at 0 0 90)
			(layer "F.SilkS")
			(hide yes)
			(effects
				(font
					(size 1.27 1.27)
				)
			)
		)
		(property "Value" ""
			(at 0 0 90)
			(layer "F.Fab")
			(effects
				(font
					(size 1.27 1.27)
				)
			)
		)
		(duplicate_pad_numbers_are_jumpers no)
		(fp_line
			(start 0.7874 -0.4064)
			(end 0.7874 0.4064)
			(stroke
				(width 0.1524)
				(type default)
			)
			(layer "F.SilkS")
		)
		(fp_line
			(start -0.7874 -0.4064)
			(end 0.7874 -0.4064)
			(stroke
				(width 0.1524)
				(type default)
			)
			(layer "F.SilkS")
		)
		(fp_line
			(start 0.7874 0.4064)
			(end -0.7874 0.4064)
			(stroke
				(width 0.1524)
				(type default)
			)
			(layer "F.SilkS")
		)
		(fp_line
			(start -0.7874 0.4064)
			(end -0.7874 -0.4064)
			(stroke
				(width 0.1524)
				(type default)
			)
			(layer "F.SilkS")
		)
		(fp_line
			(start -0.12065 -0.305054)
			(end -0.12065 -0.2794)
			(stroke
				(width 0.1)
				(type default)
			)
			(layer "F.Fab")
		)
		(fp_line
			(start -0.67945 -0.305054)
			(end -0.12065 -0.305054)
			(stroke
				(width 0.1)
				(type default)
			)
			(layer "F.Fab")
		)
		(fp_line
			(start 0.67945 -0.3048)
			(end 0.67945 0.3048)
			(stroke
				(width 0.1)
				(type default)
			)
			(layer "F.Fab")
		)
		(fp_line
			(start 0.12065 -0.3048)
			(end 0.67945 -0.3048)
			(stroke
				(width 0.1)
				(type default)
			)
			(layer "F.Fab")
		)
		(fp_line
			(start 0.12065 -0.2794)
			(end 0.12065 -0.3048)
			(stroke
				(width 0.1)
				(type default)
			)
			(layer "F.Fab")
		)
		(fp_line
			(start -0.12065 -0.2794)
			(end 0.12065 -0.2794)
			(stroke
				(width 0.1)
				(type default)
			)
			(layer "F.Fab")
		)
		(fp_line
			(start 0.120396 0.2794)
			(end -0.12065 0.2794)
			(stroke
				(width 0.1)
				(type default)
			)
			(layer "F.Fab")
		)
		(fp_line
			(start -0.12065 0.2794)
			(end -0.12065 0.3048)
			(stroke
				(width 0.1)
				(type default)
			)
			(layer "F.Fab")
		)
		(fp_line
			(start 0.67945 0.3048)
			(end 0.120396 0.3048)
			(stroke
				(width 0.1)
				(type default)
			)
			(layer "F.Fab")
		)
		(fp_line
			(start 0.120396 0.3048)
			(end 0.120396 0.2794)
			(stroke
				(width 0.1)
				(type default)
			)
			(layer "F.Fab")
		)
		(fp_line
			(start -0.12065 0.3048)
			(end -0.67945 0.3048)
			(stroke
				(width 0.1)
				(type default)
			)
			(layer "F.Fab")
		)
		(fp_line
			(start -0.67945 0.3048)
			(end -0.67945 -0.305054)
			(stroke
				(width 0.1)
				(type default)
			)
			(layer "F.Fab")
		)
		(pad "1" smd circle
			(at -0.40005 0 90)
			(size 0 0)
			(layers "F.Cu" "F.Mask" "F.Paste")
			(net "P1V8_CPU0_RT_1D")
		)
		(pad "2" smd circle
			(at 0.40005 0 90)
			(size 0 0)
			(layers "F.Cu" "F.Mask" "F.Paste")
			(net "GND")
		)
	)
	(footprint ""
		(layer "F.Cu")
		(at 89.89441 -54.69255)
		(property "Reference" "PC2149"
			(at 0 0 0)
			(layer "F.SilkS")
			(hide yes)
			(effects
				(font
					(size 1.27 1.27)
				)
			)
		)
		(property "Value" ""
			(at 0 0 0)
			(layer "F.Fab")
			(effects
				(font
					(size 1.27 1.27)
				)
			)
		)
		(duplicate_pad_numbers_are_jumpers no)
		(fp_line
			(start -0.7874 -0.4064)
			(end 0.7874 -0.4064)
			(stroke
				(width 0.1524)
				(type default)
			)
			(layer "F.SilkS")
		)
		(fp_line
			(start -0.7874 0.4064)
			(end -0.7874 -0.4064)
			(stroke
				(width 0.1524)
				(type default)
			)
			(layer "F.SilkS")
		)
		(fp_line
			(start 0.7874 -0.4064)
			(end 0.7874 0.4064)
			(stroke
				(width 0.1524)
				(type default)
			)
			(layer "F.SilkS")
		)
		(fp_line
			(start 0.7874 0.4064)
			(end -0.7874 0.4064)
			(stroke
				(width 0.1524)
				(type default)
			)
			(layer "F.SilkS")
		)
		(fp_line
			(start -0.67945 -0.305054)
			(end -0.12065 -0.305054)
			(stroke
				(width 0.1)
				(type default)
			)
			(layer "F.Fab")
		)
		(fp_line
			(start -0.67945 0.3048)
			(end -0.67945 -0.305054)
			(stroke
				(width 0.1)
				(type default)
			)
			(layer "F.Fab")
		)
		(fp_line
			(start -0.12065 -0.305054)
			(end -0.12065 -0.2794)
			(stroke
				(width 0.1)
				(type default)
			)
			(layer "F.Fab")
		)
		(fp_line
			(start -0.12065 -0.2794)
			(end 0.12065 -0.2794)
			(stroke
				(width 0.1)
				(type default)
			)
			(layer "F.Fab")
		)
		(fp_line
			(start -0.12065 0.2794)
			(end -0.12065 0.3048)
			(stroke
				(width 0.1)
				(type default)
			)
			(layer "F.Fab")
		)
		(fp_line
			(start -0.12065 0.3048)
			(end -0.67945 0.3048)
			(stroke
				(width 0.1)
				(type default)
			)
			(layer "F.Fab")
		)
		(fp_line
			(start 0.120396 0.2794)
			(end -0.12065 0.2794)
			(stroke
				(width 0.1)
				(type default)
			)
			(layer "F.Fab")
		)
		(fp_line
			(start 0.120396 0.3048)
			(end 0.120396 0.2794)
			(stroke
				(width 0.1)
				(type default)
			)
			(layer "F.Fab")
		)
		(fp_line
			(start 0.12065 -0.3048)
			(end 0.67945 -0.3048)
			(stroke
				(width 0.1)
				(type default)
			)
			(layer "F.Fab")
		)
		(fp_line
			(start 0.12065 -0.2794)
			(end 0.12065 -0.3048)
			(stroke
				(width 0.1)
				(type default)
			)
			(layer "F.Fab")
		)
		(fp_line
			(start 0.67945 -0.3048)
			(end 0.67945 0.3048)
			(stroke
				(width 0.1)
				(type default)
			)
			(layer "F.Fab")
		)
		(fp_line
			(start 0.67945 0.3048)
			(end 0.120396 0.3048)
			(stroke
				(width 0.1)
				(type default)
			)
			(layer "F.Fab")
		)
		(pad "1" smd circle
			(at -0.40005 0)
			(size 0 0)
			(layers "F.Cu" "F.Mask" "F.Paste")
			(net "P3V3_OCP_V3_2_R")
		)
		(pad "2" smd circle
			(at 0.40005 0)
			(size 0 0)
			(layers "F.Cu" "F.Mask" "F.Paste")
			(net "P3V3_OCP_GATE_2")
		)
	)
	(footprint ""
		(layer "F.Cu")
		(at 177.378106 -427.226984 180)
		(property "Reference" "R2696"
			(at 0 0 180)
			(layer "F.SilkS")
			(hide yes)
			(effects
				(font
					(size 1.27 1.27)
				)
			)
		)
		(property "Value" ""
			(at 0 0 180)
			(layer "F.Fab")
			(effects
				(font
					(size 1.27 1.27)
				)
			)
		)
		(duplicate_pad_numbers_are_jumpers no)
		(fp_line
			(start 0.7874 0.4064)
			(end -0.7874 0.4064)
			(stroke
				(width 0.1524)
				(type default)
			)
			(layer "F.SilkS")
		)
		(fp_line
			(start 0.7874 -0.4064)
			(end 0.7874 0.4064)
			(stroke
				(width 0.1524)
				(type default)
			)
			(layer "F.SilkS")
		)
		(fp_line
			(start -0.7874 0.4064)
			(end -0.7874 -0.4064)
			(stroke
				(width 0.1524)
				(type default)
			)
			(layer "F.SilkS")
		)
		(fp_line
			(start -0.7874 -0.4064)
			(end 0.7874 -0.4064)
			(stroke
				(width 0.1524)
				(type default)
			)
			(layer "F.SilkS")
		)
		(fp_line
			(start 0.67945 0.3048)
			(end 0.120396 0.3048)
			(stroke
				(width 0.1)
				(type default)
			)
			(layer "F.Fab")
		)
		(fp_line
			(start 0.67945 -0.3048)
			(end 0.67945 0.3048)
			(stroke
				(width 0.1)
				(type default)
			)
			(layer "F.Fab")
		)
		(fp_line
			(start 0.12065 -0.2794)
			(end 0.12065 -0.3048)
			(stroke
				(width 0.1)
				(type default)
			)
			(layer "F.Fab")
		)
		(fp_line
			(start 0.12065 -0.3048)
			(end 0.67945 -0.3048)
			(stroke
				(width 0.1)
				(type default)
			)
			(layer "F.Fab")
		)
		(fp_line
			(start 0.120396 0.3048)
			(end 0.120396 0.2794)
			(stroke
				(width 0.1)
				(type default)
			)
			(layer "F.Fab")
		)
		(fp_line
			(start 0.120396 0.2794)
			(end -0.12065 0.2794)
			(stroke
				(width 0.1)
				(type default)
			)
			(layer "F.Fab")
		)
		(fp_line
			(start -0.12065 0.3048)
			(end -0.67945 0.3048)
			(stroke
				(width 0.1)
				(type default)
			)
			(layer "F.Fab")
		)
		(fp_line
			(start -0.12065 0.2794)
			(end -0.12065 0.3048)
			(stroke
				(width 0.1)
				(type default)
			)
			(layer "F.Fab")
		)
		(fp_line
			(start -0.12065 -0.2794)
			(end 0.12065 -0.2794)
			(stroke
				(width 0.1)
				(type default)
			)
			(layer "F.Fab")
		)
		(fp_line
			(start -0.12065 -0.305054)
			(end -0.12065 -0.2794)
			(stroke
				(width 0.1)
				(type default)
			)
			(layer "F.Fab")
		)
		(fp_line
			(start -0.67945 0.3048)
			(end -0.67945 -0.305054)
			(stroke
				(width 0.1)
				(type default)
			)
			(layer "F.Fab")
		)
		(fp_line
			(start -0.67945 -0.305054)
			(end -0.12065 -0.305054)
			(stroke
				(width 0.1)
				(type default)
			)
			(layer "F.Fab")
		)
		(pad "1" smd circle
			(at -0.40005 0 180)
			(size 0 0)
			(layers "F.Cu" "F.Mask" "F.Paste")
			(net "TCA9539_0_ADD0")
		)
		(pad "2" smd circle
			(at 0.40005 0 180)
			(size 0 0)
			(layers "F.Cu" "F.Mask" "F.Paste")
			(net "GND")
		)
	)
)
